FILE_TYPE = CONNECTIVITY;
{Allegro Design Entry HDL 17.4-2019 S026 (4007227) 1/17/2022}
"PAGE_NUMBER" = 142;
0"NC";
1"P3V3_AUX\g";
2"LED_BIOS_DBG_MODE_N";
3"BIOS_DEBUG_MODE";
4"GND\g";
5"LED_BIOS_DBG_MODE";
6"LED_BIOS_DBG_MODE_R";
7"P3V3_AUX\g";
%"Q_LED"
"1","(-4650,1575)","0","pure_quanta","I79";
;
LOCATION"D9"
$SEC"1"
CDS_SEC"1"
MANUF_PN"LTST-C281TBKT-5A"
COLOR"LED_BLUE"
MATERIAL"IC"
PACK_TYPE"SMLF"
CDS_LIB"pure_quanta"
NEEDS_NO_SIZE"TRUE"
PART_NUMBER"BEBL0172Z00";
"A"
$PN"A"6;
"C"
$PN"C"5;
%"MOSFET_N_GSD"
"1","(-3550,1300)","2","pure_quanta","I80";
;
LOCATION"Q29"
$SEC"1"
CDS_SEC"1"
VALUE"NX138BK"
MATERIAL"IC"
PART_TYPE"SMLF"
CDS_LIB"pure_quanta"
CDS_LMAN_SYM_OUTLINE"-100,100,100,-100"
NEEDS_NO_SIZE"TRUE"
PART_NUMBER"BAM01380023";
"DRAIN"
$PN"D"5;
"SOURCE"
$PN"S"4;
"GATE"
$PN"G"2;
%"MOSFET_N_GSD"
"1","(-2525,925)","2","pure_quanta","I81";
;
LOCATION"Q30"
$SEC"1"
CDS_SEC"1"
VALUE"NX138BK"
MATERIAL"IC"
PART_TYPE"SMLF"
NEEDS_NO_SIZE"TRUE"
CDS_LMAN_SYM_OUTLINE"-100,100,100,-100"
CDS_LIB"pure_quanta"
PART_NUMBER"BAM01380023";
"DRAIN"
$PN"D"2;
"SOURCE"
$PN"S"4;
"GATE"
$PN"G"3;
%"Q_RES"
"1","(-5550,1575)","0","pure_quanta","I82";
;
LOCATION"R1444"
$SEC"1"
CDS_SEC"1"
PACK_TYPE"0402LF"
VALUE"130"
WATTAGE"1/16W"
TOLERANCE"1%"
MATERIAL"CHIP"
CDS_LIB"pure_quanta"
PART_NUMBER"CS11302FB03";
"B"
$PN"2"6;
"A"
$PN"1"7;
%"UNIVERSAL_POWER"
"1","(-5925,1825)","0","pure_quanta_power","I83";
;
HDL_POWER"P3V3_AUX"
CDS_LIB"pure_quanta_power"
BOM_COST"OCP3.0 ";
"A"7;
%"UNIVERSAL_GND"
"1","(-2550,625)","0","pure_quanta_power","I85";
;
HDL_POWER"GND"
CDS_LIB"pure_quanta_power"
BOM_COST"MISC.";
"A"4;
%"UNIVERSAL_POWER"
"1","(-2550,1725)","0","pure_quanta_power","I86";
;
HDL_POWER"P3V3_AUX"
CDS_LIB"pure_quanta_power";
"A"1;
%"Q_RES"
"2","(-2550,1500)","0","pure_quanta","I87";
;
LOCATION"R1507"
$SEC"1"
CDS_SEC"1"
PACK_TYPE"0402LF"
TOLERANCE"1%"
WATTAGE"1/16W"
MATERIAL"CHIP"
VALUE"1K"
CDS_LIB"pure_quanta"
PART_NUMBER"CS21002FB06";
"A"
$PN"1"1;
"B"
$PN"2"2;
END.
